# T6G (Grand Teton) — schematic netlist excerpt (pin names and nets, part order shuffled) for the footprints in the layout excerpt that follows; sources: Cadence DE-HDL packaged netlist, KiCad conversion of 04192023_DAF0TMB3IC0_F0TG_MB_C_brd_V02_OCP.brd

R5056  Q_RES  10K 5% EMPTY  pkg 0402LF  page 27 : A = CPU0_RTC_LDO_SELECT ; B = GND
C6673  Q_CAP_DIFFBUS  DIFF BUS_0.22UF 6.3V 20% X6S  pkg C0201  page 330 : \1\ = P5E_CPU1_P1_TX_BUF_C_DP<6> ; \2\ = P5E_CPU1_P1_TX_BUF_DP<6>
PC119_6  Q_CAP  22UF 16V 20% X6S  pkg C0805  page 203 : A = SW_P12V_AUX_PVDDCR_CPU1_P0_FLT ; B = GND
PC139_5  Q_CAP  22UF 16V 20% X6S  pkg C0805  page 203 : A = SW_P12V_AUX_PVDDCR_CPU1_P0_FLT ; B = GND

(kicad_pcb
	(version 20260206)
	(generator "pcbnew")
	(generator_version "10.0")
	(general
		(thickness 1.6)
		(legacy_teardrops no)
	)
	(paper "A4")
	(title_block
		(title "04192023_DAF0TMB3IC0_F0TG_MB_C_brd_V02_OCP.brd")
		(comment 1 "Grand Teton / footprints 6119-6122 of 8354")
	)
	(layers
		(0 "F.Cu" signal "TOP")
		(4 "In1.Cu" signal "GND")
		(6 "In2.Cu" signal "IN1")
		(8 "In3.Cu" signal "GND1")
		(10 "In4.Cu" signal "IN2")
		(12 "In5.Cu" signal "GND2")
		(14 "In6.Cu" signal "IN3")
		(16 "In7.Cu" signal "GND3")
		(18 "In8.Cu" signal "VCC")
		(20 "In9.Cu" signal "VCC1")
		(22 "In10.Cu" signal "GND4")
		(24 "In11.Cu" signal "IN4")
		(26 "In12.Cu" signal "GND5")
		(28 "In13.Cu" signal "IN5")
		(30 "In14.Cu" signal "GND6")
		(32 "In15.Cu" signal "IN6")
		(34 "In16.Cu" signal "GND7")
		(2 "B.Cu" signal "BOTTOM")
		(9 "F.Adhes" user "F.Adhesive")
		(11 "B.Adhes" user "B.Adhesive")
		(13 "F.Paste" user "Package Geometry/Pastemask Top")
		(15 "B.Paste" user "Package Geometry/Pastemask Bottom")
		(5 "F.SilkS" user "Ref Des/Silkscreen Top")
		(7 "B.SilkS" user "Ref Des/Silkscreen Bottom")
		(1 "F.Mask" user "Board Geometry/Soldermask Top")
		(3 "B.Mask" user "Board Geometry/Soldermask Bottom")
		(17 "Dwgs.User" user "User.Drawings")
		(19 "Cmts.User" user "User.Comments")
		(21 "Eco1.User" user "User.Eco1")
		(23 "Eco2.User" user "User.Eco2")
		(25 "Edge.Cuts" user "Board Geometry/Outline")
		(27 "Margin" user)
		(31 "F.CrtYd" user "Package Geometry/Place Bound Top")
		(29 "B.CrtYd" user "Package Geometry/Place Bound Bottom")
		(35 "F.Fab" user "Ref Des/Assembly Top")
		(33 "B.Fab" user "Ref Des/Assembly Bottom")
	)
	(footprint ""
		(layer "B.Cu")
		(at 352.787712 -340.002368 90)
		(property "Reference" "PC119_6"
			(at 0 0 90)
			(layer "B.SilkS")
			(hide yes)
			(effects
				(font
					(size 1.27 1.27)
				)
				(justify mirror)
			)
		)
		(property "Value" ""
			(at 0 0 90)
			(layer "B.Fab")
			(effects
				(font
					(size 1.27 1.27)
				)
				(justify mirror)
			)
		)
		(duplicate_pad_numbers_are_jumpers no)
		(fp_line
			(start 1.524 -0.762)
			(end -1.524 -0.762)
			(stroke
				(width 0.1524)
				(type default)
			)
			(layer "B.SilkS")
		)
		(fp_line
			(start -1.524 -0.762)
			(end -1.524 0.762)
			(stroke
				(width 0.1524)
				(type default)
			)
			(layer "B.SilkS")
		)
		(fp_line
			(start 1.524 0.762)
			(end 1.524 -0.762)
			(stroke
				(width 0.1524)
				(type default)
			)
			(layer "B.SilkS")
		)
		(fp_line
			(start -1.524 0.762)
			(end 1.524 0.762)
			(stroke
				(width 0.1524)
				(type default)
			)
			(layer "B.SilkS")
		)
		(fp_line
			(start 1.1049 -0.724916)
			(end 1.1049 0.724916)
			(stroke
				(width 0.1)
				(type default)
			)
			(layer "B.Fab")
		)
		(fp_line
			(start -1.1049 -0.724916)
			(end 1.1049 -0.724916)
			(stroke
				(width 0.1)
				(type default)
			)
			(layer "B.Fab")
		)
		(fp_line
			(start 1.1049 0.724916)
			(end -1.1049 0.724916)
			(stroke
				(width 0.1)
				(type default)
			)
			(layer "B.Fab")
		)
		(fp_line
			(start -1.1049 0.724916)
			(end -1.1049 -0.724916)
			(stroke
				(width 0.1)
				(type default)
			)
			(layer "B.Fab")
		)
		(pad "1" smd rect
			(at 0.889 0 90)
			(size 1.016 1.27)
			(layers "B.Cu" "B.Mask" "B.Paste")
			(net "SW_P12V_AUX_PVDDCR_CPU1_P0_FLT")
		)
		(pad "2" smd rect
			(at -0.889 0 90)
			(size 1.016 1.27)
			(layers "B.Cu" "B.Mask" "B.Paste")
			(net "GND")
		)
	)
	(footprint ""
		(layer "B.Cu")
		(at 68.594224 -408.517344 90)
		(property "Reference" "C6673"
			(at 0 0 90)
			(layer "B.SilkS")
			(hide yes)
			(effects
				(font
					(size 1.27 1.27)
				)
				(justify mirror)
			)
		)
		(property "Value" ""
			(at 0 0 90)
			(layer "B.Fab")
			(effects
				(font
					(size 1.27 1.27)
				)
				(justify mirror)
			)
		)
		(duplicate_pad_numbers_are_jumpers no)
		(fp_line
			(start 0.299974 -0.150114)
			(end -0.299974 -0.150114)
			(stroke
				(width 0.1)
				(type default)
			)
			(layer "B.Fab")
		)
		(fp_line
			(start -0.299974 -0.150114)
			(end -0.299974 0.150114)
			(stroke
				(width 0.1)
				(type default)
			)
			(layer "B.Fab")
		)
		(fp_line
			(start 0.299974 0.150114)
			(end 0.299974 -0.150114)
			(stroke
				(width 0.1)
				(type default)
			)
			(layer "B.Fab")
		)
		(fp_line
			(start -0.299974 0.150114)
			(end 0.299974 0.150114)
			(stroke
				(width 0.1)
				(type default)
			)
			(layer "B.Fab")
		)
		(pad "1" smd rect
			(at 0.2667 0 270)
			(size 0.3048 0.381)
			(layers "B.Cu" "B.Mask" "B.Paste")
			(net "P5E_CPU1_P1_TX_BUF_C_DP<6>")
		)
		(pad "2" smd rect
			(at -0.2667 0 270)
			(size 0.3048 0.381)
			(layers "B.Cu" "B.Mask" "B.Paste")
			(net "P5E_CPU1_P1_TX_BUF_DP<6>")
		)
	)
	(footprint ""
		(layer "B.Cu")
		(at 346.639896 -335.092294 90)
		(property "Reference" "PC139_5"
			(at 0 0 90)
			(layer "B.SilkS")
			(hide yes)
			(effects
				(font
					(size 1.27 1.27)
				)
				(justify mirror)
			)
		)
		(property "Value" ""
			(at 0 0 90)
			(layer "B.Fab")
			(effects
				(font
					(size 1.27 1.27)
				)
				(justify mirror)
			)
		)
		(duplicate_pad_numbers_are_jumpers no)
		(fp_line
			(start 1.524 -0.762)
			(end -1.524 -0.762)
			(stroke
				(width 0.1524)
				(type default)
			)
			(layer "B.SilkS")
		)
		(fp_line
			(start -1.524 -0.762)
			(end -1.524 0.762)
			(stroke
				(width 0.1524)
				(type default)
			)
			(layer "B.SilkS")
		)
		(fp_line
			(start 1.524 0.762)
			(end 1.524 -0.762)
			(stroke
				(width 0.1524)
				(type default)
			)
			(layer "B.SilkS")
		)
		(fp_line
			(start -1.524 0.762)
			(end 1.524 0.762)
			(stroke
				(width 0.1524)
				(type default)
			)
			(layer "B.SilkS")
		)
		(fp_line
			(start 1.1049 -0.724916)
			(end 1.1049 0.724916)
			(stroke
				(width 0.1)
				(type default)
			)
			(layer "B.Fab")
		)
		(fp_line
			(start -1.1049 -0.724916)
			(end 1.1049 -0.724916)
			(stroke
				(width 0.1)
				(type default)
			)
			(layer "B.Fab")
		)
		(fp_line
			(start 1.1049 0.724916)
			(end -1.1049 0.724916)
			(stroke
				(width 0.1)
				(type default)
			)
			(layer "B.Fab")
		)
		(fp_line
			(start -1.1049 0.724916)
			(end -1.1049 -0.724916)
			(stroke
				(width 0.1)
				(type default)
			)
			(layer "B.Fab")
		)
		(pad "1" smd rect
			(at 0.889 0 90)
			(size 1.016 1.27)
			(layers "B.Cu" "B.Mask" "B.Paste")
			(net "SW_P12V_AUX_PVDDCR_CPU1_P0_FLT")
		)
		(pad "2" smd rect
			(at -0.889 0 90)
			(size 1.016 1.27)
			(layers "B.Cu" "B.Mask" "B.Paste")
			(net "GND")
		)
	)
	(footprint ""
		(layer "B.Cu")
		(at 408.597608 -327.866502 90)
		(property "Reference" "R5056"
			(at 0 0 90)
			(layer "B.SilkS")
			(hide yes)
			(effects
				(font
					(size 1.27 1.27)
				)
				(justify mirror)
			)
		)
		(property "Value" ""
			(at 0 0 90)
			(layer "B.Fab")
			(effects
				(font
					(size 1.27 1.27)
				)
				(justify mirror)
			)
		)
		(duplicate_pad_numbers_are_jumpers no)
		(fp_line
			(start 0.7874 -0.4064)
			(end -0.7874 -0.4064)
			(stroke
				(width 0.1524)
				(type default)
			)
			(layer "B.SilkS")
		)
		(fp_line
			(start -0.7874 -0.4064)
			(end -0.7874 0.4064)
			(stroke
				(width 0.1524)
				(type default)
			)
			(layer "B.SilkS")
		)
		(fp_line
			(start 0.7874 0.4064)
			(end 0.7874 -0.4064)
			(stroke
				(width 0.1524)
				(type default)
			)
			(layer "B.SilkS")
		)
		(fp_line
			(start -0.7874 0.4064)
			(end 0.7874 0.4064)
			(stroke
				(width 0.1524)
				(type default)
			)
			(layer "B.SilkS")
		)
		(fp_line
			(start 0.67945 -0.305054)
			(end 0.12065 -0.305054)
			(stroke
				(width 0.1)
				(type default)
			)
			(layer "B.Fab")
		)
		(fp_line
			(start 0.12065 -0.305054)
			(end 0.12065 -0.2794)
			(stroke
				(width 0.1)
				(type default)
			)
			(layer "B.Fab")
		)
		(fp_line
			(start -0.12065 -0.3048)
			(end -0.67945 -0.3048)
			(stroke
				(width 0.1)
				(type default)
			)
			(layer "B.Fab")
		)
		(fp_line
			(start -0.67945 -0.3048)
			(end -0.67945 0.3048)
			(stroke
				(width 0.1)
				(type default)
			)
			(layer "B.Fab")
		)
		(fp_line
			(start 0.12065 -0.2794)
			(end -0.12065 -0.2794)
			(stroke
				(width 0.1)
				(type default)
			)
			(layer "B.Fab")
		)
		(fp_line
			(start -0.12065 -0.2794)
			(end -0.12065 -0.3048)
			(stroke
				(width 0.1)
				(type default)
			)
			(layer "B.Fab")
		)
		(fp_line
			(start 0.12065 0.2794)
			(end 0.12065 0.3048)
			(stroke
				(width 0.1)
				(type default)
			)
			(layer "B.Fab")
		)
		(fp_line
			(start -0.120396 0.2794)
			(end 0.12065 0.2794)
			(stroke
				(width 0.1)
				(type default)
			)
			(layer "B.Fab")
		)
		(fp_line
			(start 0.67945 0.3048)
			(end 0.67945 -0.305054)
			(stroke
				(width 0.1)
				(type default)
			)
			(layer "B.Fab")
		)
		(fp_line
			(start 0.12065 0.3048)
			(end 0.67945 0.3048)
			(stroke
				(width 0.1)
				(type default)
			)
			(layer "B.Fab")
		)
		(fp_line
			(start -0.120396 0.3048)
			(end -0.120396 0.2794)
			(stroke
				(width 0.1)
				(type default)
			)
			(layer "B.Fab")
		)
		(fp_line
			(start -0.67945 0.3048)
			(end -0.120396 0.3048)
			(stroke
				(width 0.1)
				(type default)
			)
			(layer "B.Fab")
		)
		(pad "1" smd circle
			(at 0.40005 0 270)
			(size 0 0)
			(layers "B.Cu" "B.Mask" "B.Paste")
			(net "CPU0_RTC_LDO_SELECT")
		)
		(pad "2" smd circle
			(at -0.40005 0 270)
			(size 0 0)
			(layers "B.Cu" "B.Mask" "B.Paste")
			(net "GND")
		)
	)
)
